(kicad_pcb
	(version 20241229)
	(generator "pcbnew")
	(generator_version "9.0")
	(general
		(thickness 1.61)
		(legacy_teardrops no)
	)
	(paper "A3")
	(title_block
		(title "SO-DIMM DDR5 Tester")
		(date "2025-11-26")
		(rev "1.3.0")
		(comment 9 "footprints 60-65 of 627")
	)
	(layers
		(0 "F.Cu" signal)
		(4 "In1.Cu" power)
		(6 "In2.Cu" mixed)
		(8 "In3.Cu" power)
		(10 "In4.Cu" mixed)
		(12 "In5.Cu" power)
		(14 "In6.Cu" mixed)
		(16 "In7.Cu" power)
		(18 "In8.Cu" power)
		(20 "In9.Cu" mixed)
		(22 "In10.Cu" power)
		(2 "B.Cu" signal)
		(9 "F.Adhes" user "F.Adhesive")
		(11 "B.Adhes" user "B.Adhesive")
		(13 "F.Paste" user)
		(15 "B.Paste" user)
		(5 "F.SilkS" user "F.Silkscreen")
		(7 "B.SilkS" user "B.Silkscreen")
		(1 "F.Mask" user)
		(3 "B.Mask" user)
		(17 "Dwgs.User" user "User.Drawings")
		(19 "Cmts.User" user "User.Comments")
		(21 "Eco1.User" user "User.Eco1")
		(23 "Eco2.User" user "User.Eco2")
		(25 "Edge.Cuts" user)
		(27 "Margin" user)
		(31 "F.CrtYd" user "F.Courtyard")
		(29 "B.CrtYd" user "B.Courtyard")
		(35 "F.Fab" user)
		(33 "B.Fab" user)
	)
	(footprint "antmicro-footprints:R_0402_1005Metric"
		(layer "F.Cu")
		(at 91.2 178)
		(descr "Resistor SMD 0402")
		(tags "resistor SMD 0402")
		(property "Reference" "R43"
			(at -1.122484 -0.772697 0)
			(layer "F.SilkS")
			(hide yes)
			(effects
				(font
					(size 0.7 0.7)
					(thickness 0.15)
				)
				(justify left bottom)
			)
		)
		(property "Value" "R_10k_0402"
			(at -1.011843 1.772047 0)
			(layer "F.Fab")
			(effects
				(font
					(size 0.7 0.7)
					(thickness 0.15)
				)
				(justify left bottom)
			)
		)
		(property "Datasheet" "https://www.bourns.com/docs/product-datasheets/cr.pdf"
			(at 0 0 0)
			(layer "F.Fab")
			(hide yes)
			(effects
				(font
					(size 1.27 1.27)
					(thickness 0.15)
				)
			)
		)
		(property "Author" "Antmicro"
			(at 0 0 0)
			(layer "F.Fab")
			(hide yes)
			(effects
				(font
					(size 1 1)
					(thickness 0.15)
				)
			)
		)
		(property "License" "Apache-2.0"
			(at 0 0 0)
			(layer "F.Fab")
			(hide yes)
			(effects
				(font
					(size 1 1)
					(thickness 0.15)
				)
			)
		)
		(property "MPN" "CR0402-FX-1002GLF"
			(at 0 0 0)
			(layer "F.Fab")
			(hide yes)
			(effects
				(font
					(size 1 1)
					(thickness 0.15)
				)
			)
		)
		(property "Manufacturer" "Bourns"
			(at 0 0 0)
			(layer "F.Fab")
			(hide yes)
			(effects
				(font
					(size 1 1)
					(thickness 0.15)
				)
			)
		)
		(property "Tolerance" "1%"
			(at 0 0 0)
			(layer "F.Fab")
			(hide yes)
			(effects
				(font
					(size 1 1)
					(thickness 0.15)
				)
			)
		)
		(property "Val" "10k"
			(at 0 0 0)
			(layer "F.Fab")
			(hide yes)
			(effects
				(font
					(size 1 1)
					(thickness 0.15)
				)
			)
		)
		(sheetname "/Debug FTDI/")
		(sheetfile "debug-ftdi.kicad_sch")
		(attr smd)
		(fp_rect
			(start -0.93 -0.47)
			(end 0.93 0.47)
			(stroke
				(width 0.05)
				(type solid)
			)
			(fill no)
			(layer "F.CrtYd")
		)
		(fp_rect
			(start -0.5 -0.25)
			(end 0.5 0.25)
			(stroke
				(width 0.15)
				(type solid)
			)
			(fill no)
			(layer "F.Fab")
		)
		(pad "1" smd roundrect
			(at -0.485 0)
			(size 0.59 0.64)
			(layers "F.Cu" "F.Mask" "F.Paste")
			(roundrect_rratio 0.25)
			(net 6 "/Debug FTDI/FTDI_3V3")
			(pintype "passive")
		)
		(pad "2" smd roundrect
			(at 0.485 0)
			(size 0.59 0.64)
			(layers "F.Cu" "F.Mask" "F.Paste")
			(roundrect_rratio 0.25)
			(net 370 "Net-(U6-~{RESET})")
			(pintype "passive")
		)
	)
	(footprint "antmicro-footprints:C_0805_2012Metric"
		(layer "F.Cu")
		(at 172.9195 199.314502)
		(descr "Capacitor SMD 0805")
		(tags "capacitor SMD 0805")
		(property "Reference" "C200"
			(at -2.10551 -1.198678 0)
			(layer "F.SilkS")
			(hide yes)
			(effects
				(font
					(size 0.7 0.7)
					(thickness 0.15)
				)
				(justify left bottom)
			)
		)
		(property "Value" "C_22u_25V_0805"
			(at -2.055717 1.963152 0)
			(layer "F.Fab")
			(effects
				(font
					(size 0.7 0.7)
					(thickness 0.15)
				)
				(justify left bottom)
			)
		)
		(property "Datasheet" "https://product.samsungsem.com/mlcc/CL21A226MAYNNN.do"
			(at 0 0 0)
			(layer "F.Fab")
			(hide yes)
			(effects
				(font
					(size 1.27 1.27)
					(thickness 0.15)
				)
			)
		)
		(property "Author" "Antmicro"
			(at 0 0 0)
			(layer "F.Fab")
			(hide yes)
			(effects
				(font
					(size 1 1)
					(thickness 0.15)
				)
			)
		)
		(property "Dielectric" ""
			(at 0 0 0)
			(layer "F.Fab")
			(hide yes)
			(effects
				(font
					(size 1 1)
					(thickness 0.15)
				)
			)
		)
		(property "License" "Apache-2.0"
			(at 0 0 0)
			(layer "F.Fab")
			(hide yes)
			(effects
				(font
					(size 1 1)
					(thickness 0.15)
				)
			)
		)
		(property "MPN" "CL21A226MAYNNNE"
			(at 0 0 0)
			(layer "F.Fab")
			(hide yes)
			(effects
				(font
					(size 1 1)
					(thickness 0.15)
				)
			)
		)
		(property "Manufacturer" "Samsung Electro-Mechanics"
			(at 0 0 0)
			(layer "F.Fab")
			(hide yes)
			(effects
				(font
					(size 1 1)
					(thickness 0.15)
				)
			)
		)
		(property "Val" "22u_25V"
			(at 0 0 0)
			(layer "F.Fab")
			(hide yes)
			(effects
				(font
					(size 1 1)
					(thickness 0.15)
				)
			)
		)
		(property "Voltage" ""
			(at 0 0 0)
			(layer "F.Fab")
			(hide yes)
			(effects
				(font
					(size 1 1)
					(thickness 0.15)
				)
			)
		)
		(sheetname "/Supply/")
		(sheetfile "supply.kicad_sch")
		(attr smd)
		(fp_line
			(start -0.3 -0.8)
			(end 0.3 -0.8)
			(stroke
				(width 0.15)
				(type solid)
			)
			(layer "F.SilkS")
		)
		(fp_line
			(start -0.3 0.8)
			(end 0.3 0.8)
			(stroke
				(width 0.15)
				(type solid)
			)
			(layer "F.SilkS")
		)
		(fp_rect
			(start -1.9 -0.93)
			(end 1.9 0.93)
			(stroke
				(width 0.05)
				(type solid)
			)
			(fill no)
			(layer "F.CrtYd")
		)
		(fp_rect
			(start -0.95 -0.675)
			(end 0.95 0.675)
			(stroke
				(width 0.15)
				(type solid)
			)
			(fill no)
			(layer "F.Fab")
		)
		(pad "1" smd rect
			(at -1.05 0)
			(size 1.2 1.2)
			(layers "F.Cu" "F.Mask" "F.Paste")
			(net 1 "GND")
			(pintype "passive")
		)
		(pad "2" smd rect
			(at 1.05 0)
			(size 1.2 1.2)
			(layers "F.Cu" "F.Mask" "F.Paste")
			(net 38 "VDC")
			(pintype "passive")
		)
	)
	(footprint "antmicro-footprints:R_0402_1005Metric"
		(layer "F.Cu")
		(at 98.78 136.07 -90)
		(descr "Resistor SMD 0402")
		(tags "resistor SMD 0402")
		(property "Reference" "R124"
			(at -1.122484 -0.772697 270)
			(layer "F.SilkS")
			(hide yes)
			(effects
				(font
					(size 0.7 0.7)
					(thickness 0.15)
				)
				(justify left bottom)
			)
		)
		(property "Value" "R_4k7_0402"
			(at -1.011843 1.772047 270)
			(layer "F.Fab")
			(effects
				(font
					(size 0.7 0.7)
					(thickness 0.15)
				)
				(justify left bottom)
			)
		)
		(property "Datasheet" "https://www.bourns.com/docs/product-datasheets/cr.pdf"
			(at 0 0 270)
			(layer "F.Fab")
			(hide yes)
			(effects
				(font
					(size 1.27 1.27)
					(thickness 0.15)
				)
			)
		)
		(property "Author" "Antmicro"
			(at -37.29 234.85 0)
			(layer "F.Fab")
			(hide yes)
			(effects
				(font
					(size 1 1)
					(thickness 0.15)
				)
			)
		)
		(property "License" "Apache-2.0"
			(at -37.29 234.85 0)
			(layer "F.Fab")
			(hide yes)
			(effects
				(font
					(size 1 1)
					(thickness 0.15)
				)
			)
		)
		(property "MPN" "CR0402-FX-4701GLF"
			(at -37.29 234.85 0)
			(layer "F.Fab")
			(hide yes)
			(effects
				(font
					(size 1 1)
					(thickness 0.15)
				)
			)
		)
		(property "Manufacturer" "Bourns"
			(at -37.29 234.85 0)
			(layer "F.Fab")
			(hide yes)
			(effects
				(font
					(size 1 1)
					(thickness 0.15)
				)
			)
		)
		(property "Tolerance" "1%"
			(at -37.29 234.85 0)
			(layer "F.Fab")
			(hide yes)
			(effects
				(font
					(size 1 1)
					(thickness 0.15)
				)
			)
		)
		(property "Val" "4k7"
			(at -37.29 234.85 0)
			(layer "F.Fab")
			(hide yes)
			(effects
				(font
					(size 1 1)
					(thickness 0.15)
				)
			)
		)
		(sheetname "/I^{2}C/")
		(sheetfile "i2c.kicad_sch")
		(attr smd)
		(fp_rect
			(start -0.93 -0.47)
			(end 0.93 0.47)
			(stroke
				(width 0.05)
				(type solid)
			)
			(fill no)
			(layer "F.CrtYd")
		)
		(fp_rect
			(start -0.5 -0.25)
			(end 0.5 0.25)
			(stroke
				(width 0.15)
				(type solid)
			)
			(fill no)
			(layer "F.Fab")
		)
		(pad "1" smd roundrect
			(at -0.485 0 270)
			(size 0.59 0.64)
			(layers "F.Cu" "F.Mask" "F.Paste")
			(roundrect_rratio 0.25)
			(net 267 "VDDSPD")
			(pintype "passive")
		)
		(pad "2" smd roundrect
			(at 0.485 0 270)
			(size 0.59 0.64)
			(layers "F.Cu" "F.Mask" "F.Paste")
			(roundrect_rratio 0.25)
			(net 54 "/DDR5 SODIMM/DDR.SDA")
			(pintype "passive")
		)
	)
	(footprint "antmicro-footprints:SC70-3"
		(layer "F.Cu")
		(at 97.700501 129.235461 90)
		(property "Reference" "Q1"
			(at 0 -1.6 90)
			(layer "F.SilkS")
			(hide yes)
			(effects
				(font
					(size 0.7 0.7)
					(thickness 0.15)
				)
				(justify left bottom)
			)
		)
		(property "Value" "BSS138PW,115"
			(at 0 2.3 90)
			(layer "F.Fab")
			(effects
				(font
					(size 0.7 0.7)
					(thickness 0.15)
				)
				(justify left bottom)
			)
		)
		(property "Datasheet" "https://assets.nexperia.com/documents/data-sheet/BSS138PW.pdf"
			(at 0 0 90)
			(layer "F.Fab")
			(hide yes)
			(effects
				(font
					(size 1.27 1.27)
					(thickness 0.15)
				)
			)
		)
		(property "Description" "Power MOSFET, N Channel, 60 V, 320 mA, 0.9 ohm, SOT-323, Surface Mount"
			(at 0 0 90)
			(layer "F.Fab")
			(hide yes)
			(effects
				(font
					(size 1.27 1.27)
					(thickness 0.15)
				)
			)
		)
		(property "Author" "Antmicro"
			(at 226.935962 31.53496 0)
			(layer "F.Fab")
			(hide yes)
			(effects
				(font
					(size 1 1)
					(thickness 0.15)
				)
			)
		)
		(property "License" "Apache-2.0"
			(at 226.935962 31.53496 0)
			(layer "F.Fab")
			(hide yes)
			(effects
				(font
					(size 1 1)
					(thickness 0.15)
				)
			)
		)
		(property "MPN" "BSS138PW,115"
			(at 226.935962 31.53496 0)
			(layer "F.Fab")
			(hide yes)
			(effects
				(font
					(size 1 1)
					(thickness 0.15)
				)
			)
		)
		(property "Manufacturer" "Nexperia"
			(at 226.935962 31.53496 0)
			(layer "F.Fab")
			(hide yes)
			(effects
				(font
					(size 1 1)
					(thickness 0.15)
				)
			)
		)
		(sheetname "/FPGA Config/")
		(sheetfile "fpga-config.kicad_sch")
		(attr smd)
		(fp_line
			(start -0.3 -1)
			(end 0.627 -0.999)
			(stroke
				(width 0.15)
				(type solid)
			)
			(layer "F.SilkS")
		)
		(fp_line
			(start 0.627 -0.6)
			(end 0.627 -0.999)
			(stroke
				(width 0.15)
				(type solid)
			)
			(layer "F.SilkS")
		)
		(fp_line
			(start 0.627 0.6)
			(end 0.627 1.001)
			(stroke
				(width 0.15)
				(type solid)
			)
			(layer "F.SilkS")
		)
		(fp_line
			(start -0.3 1)
			(end 0.627 1.001)
			(stroke
				(width 0.15)
				(type solid)
			)
			(layer "F.SilkS")
		)
		(fp_line
			(start 0.9 -1.3)
			(end 0.9 -0.4)
			(stroke
				(width 0.05)
				(type solid)
			)
			(layer "F.CrtYd")
		)
		(fp_line
			(start -0.9 -1.3)
			(end 0.9 -1.3)
			(stroke
				(width 0.05)
				(type solid)
			)
			(layer "F.CrtYd")
		)
		(fp_line
			(start -0.9 -1.3)
			(end -0.9 -1)
			(stroke
				(width 0.05)
				(type solid)
			)
			(layer "F.CrtYd")
		)
		(fp_line
			(start -0.9 -1)
			(end -1.4 -1)
			(stroke
				(width 0.05)
				(type solid)
			)
			(layer "F.CrtYd")
		)
		(fp_line
			(start 1.4 -0.4)
			(end 1.4 0.4)
			(stroke
				(width 0.05)
				(type solid)
			)
			(layer "F.CrtYd")
		)
		(fp_line
			(start 0.9 -0.4)
			(end 1.4 -0.4)
			(stroke
				(width 0.05)
				(type solid)
			)
			(layer "F.CrtYd")
		)
		(fp_line
			(start 1.4 0.4)
			(end 0.9 0.4)
			(stroke
				(width 0.05)
				(type solid)
			)
			(layer "F.CrtYd")
		)
		(fp_line
			(start 0.9 0.4)
			(end 0.9 1.3)
			(stroke
				(width 0.05)
				(type solid)
			)
			(layer "F.CrtYd")
		)
		(fp_line
			(start -0.9 1)
			(end -1.4 1)
			(stroke
				(width 0.05)
				(type solid)
			)
			(layer "F.CrtYd")
		)
		(fp_line
			(start -1.4 1)
			(end -1.4 -1)
			(stroke
				(width 0.05)
				(type solid)
			)
			(layer "F.CrtYd")
		)
		(fp_line
			(start 0.9 1.3)
			(end -0.9 1.3)
			(stroke
				(width 0.05)
				(type solid)
			)
			(layer "F.CrtYd")
		)
		(fp_line
			(start -0.9 1.3)
			(end -0.9 1)
			(stroke
				(width 0.05)
				(type solid)
			)
			(layer "F.CrtYd")
		)
		(fp_rect
			(start -0.623 -0.999)
			(end 0.627 1.001)
			(stroke
				(width 0.15)
				(type solid)
			)
			(fill no)
			(layer "F.Fab")
		)
		(pad "1" smd rect
			(at -1.051 -0.65 180)
			(size 0.6 0.6)
			(layers "F.Cu" "F.Mask" "F.Paste")
			(net 240 "POWER")
			(pinfunction "G")
			(pintype "input")
		)
		(pad "2" smd rect
			(at -1.051 0.65 180)
			(size 0.6 0.6)
			(layers "F.Cu" "F.Mask" "F.Paste")
			(net 1 "GND")
			(pinfunction "S")
			(pintype "passive")
		)
		(pad "3" smd rect
			(at 1.05 0 180)
			(size 0.6 0.6)
			(layers "F.Cu" "F.Mask" "F.Paste")
			(net 347 "Net-(Q1-D)")
			(pinfunction "D")
			(pintype "passive")
		)
	)
	(footprint "antmicro-footprints:TP_SMD_1mm"
		(layer "F.Cu")
		(at 186.5 137)
		(property "Reference" "TP16"
			(at 0 -0.731898 0)
			(layer "F.SilkS")
			(hide yes)
			(effects
				(font
					(size 0.7 0.7)
					(thickness 0.15)
				)
				(justify left bottom)
			)
		)
		(property "Value" "TP_1mm_SMD"
			(at 0 1.4 0)
			(layer "F.Fab")
			(effects
				(font
					(size 0.7 0.7)
					(thickness 0.15)
				)
				(justify left bottom)
			)
		)
		(property "Author" "Antmicro"
			(at 0 0 0)
			(layer "F.Fab")
			(hide yes)
			(effects
				(font
					(size 1 1)
					(thickness 0.15)
				)
			)
		)
		(property "License" "Apache-2.0"
			(at 0 0 0)
			(layer "F.Fab")
			(hide yes)
			(effects
				(font
					(size 1 1)
					(thickness 0.15)
				)
			)
		)
		(property "MPN" ""
			(at 0 0 0)
			(layer "F.Fab")
			(hide yes)
			(effects
				(font
					(size 1 1)
					(thickness 0.15)
				)
			)
		)
		(property "Manufacturer" ""
			(at 0 0 0)
			(layer "F.Fab")
			(hide yes)
			(effects
				(font
					(size 1 1)
					(thickness 0.15)
				)
			)
		)
		(sheetname "/Supply/")
		(sheetfile "supply.kicad_sch")
		(attr exclude_from_pos_files)
		(pad "1" smd circle
			(at 0 0)
			(size 1 1)
			(layers "F.Cu" "F.Mask")
			(net 38 "VDC")
			(pinfunction "1")
			(pintype "passive")
		)
	)
	(footprint "antmicro-footprints:R_1206_3216Metric"
		(layer "F.Cu")
		(at 199.5 177.173 180)
		(property "Reference" "R143"
			(at 0.45 1.223 180)
			(layer "F.SilkS")
			(effects
				(font
					(size 0.7 0.7)
					(thickness 0.15)
				)
				(justify left bottom)
			)
		)
		(property "Value" "R_0R01_1206"
			(at -2.422356 2.103591 180)
			(layer "F.Fab")
			(effects
				(font
					(size 0.7 0.7)
					(thickness 0.15)
				)
				(justify left bottom)
			)
		)
		(property "Datasheet" "https://www.yageo.com/upload/media/product/productsearch/datasheet/rchip/PYu-RL_Group_521_RoHS_L_2.pdf"
			(at 0 0 180)
			(layer "F.Fab")
			(hide yes)
			(effects
				(font
					(size 1.27 1.27)
					(thickness 0.15)
				)
			)
		)
		(property "Author" "Antmicro"
			(at 399 354.346 0)
			(layer "F.Fab")
			(hide yes)
			(effects
				(font
					(size 1 1)
					(thickness 0.15)
				)
			)
		)
		(property "License" "Apache-2.0"
			(at 399 354.346 0)
			(layer "F.Fab")
			(hide yes)
			(effects
				(font
					(size 1 1)
					(thickness 0.15)
				)
			)
		)
		(property "MPN" "RL1206FR-7W0R01L"
			(at 399 354.346 0)
			(layer "F.Fab")
			(hide yes)
			(effects
				(font
					(size 1 1)
					(thickness 0.15)
				)
			)
		)
		(property "Manufacturer" "YAGEO"
			(at 399 354.346 0)
			(layer "F.Fab")
			(hide yes)
			(effects
				(font
					(size 1 1)
					(thickness 0.15)
				)
			)
		)
		(property "Tolerance" "1%"
			(at 399 354.346 0)
			(layer "F.Fab")
			(hide yes)
			(effects
				(font
					(size 1 1)
					(thickness 0.15)
				)
			)
		)
		(property "Val" "0R01"
			(at 399 354.346 0)
			(layer "F.Fab")
			(hide yes)
			(effects
				(font
					(size 1 1)
					(thickness 0.15)
				)
			)
		)
		(sheetname "/Supply/")
		(sheetfile "supply.kicad_sch")
		(attr smd)
		(fp_line
			(start 0 0.9)
			(end 0.498 0.9)
			(stroke
				(width 0.15)
				(type solid)
			)
			(layer "F.SilkS")
		)
		(fp_line
			(start 0 0.9)
			(end -0.5 0.9)
			(stroke
				(width 0.15)
				(type solid)
			)
			(layer "F.SilkS")
		)
		(fp_line
			(start 0 -0.902)
			(end 0.498 -0.902)
			(stroke
				(width 0.15)
				(type solid)
			)
			(layer "F.SilkS")
		)
		(fp_line
			(start 0 -0.902)
			(end -0.5 -0.902)
			(stroke
				(width 0.15)
				(type solid)
			)
			(layer "F.SilkS")
		)
		(fp_rect
			(start -2.25 -1.05)
			(end 2.25 1.05)
			(stroke
				(width 0.05)
				(type solid)
			)
			(fill no)
			(layer "F.CrtYd")
		)
		(fp_line
			(start 1.6 -0.802)
			(end 1.6 0.8)
			(stroke
				(width 0.15)
				(type solid)
			)
			(layer "F.Fab")
		)
		(fp_line
			(start -1.601 0.8)
			(end 1.6 0.8)
			(stroke
				(width 0.15)
				(type solid)
			)
			(layer "F.Fab")
		)
		(fp_line
			(start -1.601 -0.802)
			(end 1.6 -0.802)
			(stroke
				(width 0.15)
				(type solid)
			)
			(layer "F.Fab")
		)
		(fp_line
			(start -1.601 -0.802)
			(end -1.601 0.8)
			(stroke
				(width 0.15)
				(type solid)
			)
			(layer "F.Fab")
		)
		(pad "1" smd roundrect
			(at -1.5 0 180)
			(size 1.2 1.8)
			(layers "F.Cu" "F.Mask" "F.Paste")
			(roundrect_rratio 0.15)
			(net 35 "/Supply/spare_local")
			(pintype "passive")
		)
		(pad "2" smd roundrect
			(at 1.499 0 180)
			(size 1.2 1.8)
			(layers "F.Cu" "F.Mask" "F.Paste")
			(roundrect_rratio 0.15)
			(net 239 "/Supply/spare")
			(pintype "passive")
		)
	)
)
